# BASEBOARD_FAB2 (Tioga Pass) — schematic netlist excerpt (pin names and nets, part order shuffled) for the footprints in the layout excerpt that follows; sources: Cadence DE-HDL packaged netlist, KiCad conversion of Wiwynn_Tioga_Pass_MB.brd

C6P4  CAP_A  0.1UF 16V 10% X7R  pkg 0402V  page 102 : A = P3V3_DB1200 ; B = GND
R6P12  RES  42.2 1.0% EMPTY  pkg 0402  page 103 : A = CLK_100M_CPU0_BCLK2_DN ; B = GND
FB2M1  FERRITE  120 FB  pkg SM  page 127 : A = P1V05_PCH_STBY ; B = P1V05_PCH_STBY_WM20_PLL

(kicad_pcb
	(version 20260206)
	(generator "pcbnew")
	(generator_version "10.0")
	(general
		(thickness 1.6)
		(legacy_teardrops no)
	)
	(paper "A4")
	(title_block
		(title "Wiwynn_Tioga_Pass_MB.brd")
		(comment 1 "Tioga Pass / footprints 3337-3339 of 4770")
	)
	(layers
		(0 "F.Cu" signal "TOP")
		(4 "In1.Cu" signal "L2GND")
		(6 "In2.Cu" signal "L3")
		(8 "In3.Cu" signal "L4GND")
		(10 "In4.Cu" signal "L5")
		(12 "In5.Cu" signal "L6GND")
		(14 "In6.Cu" signal "L7VCC")
		(16 "In7.Cu" signal "L8VCC")
		(18 "In8.Cu" signal "L9GND")
		(20 "In9.Cu" signal "L10")
		(22 "In10.Cu" signal "L11GND")
		(24 "In11.Cu" signal "L12")
		(26 "In12.Cu" signal "L13GND")
		(2 "B.Cu" signal "BOTTOM")
		(9 "F.Adhes" user "F.Adhesive")
		(11 "B.Adhes" user "B.Adhesive")
		(13 "F.Paste" user "Package Geometry/Pastemask Top")
		(15 "B.Paste" user "Package Geometry/Pastemask Bottom")
		(5 "F.SilkS" user "Ref Des/Silkscreen Top")
		(7 "B.SilkS" user "Ref Des/Silkscreen Bottom")
		(1 "F.Mask" user "Board Geometry/Soldermask Top")
		(3 "B.Mask" user "Board Geometry/Soldermask Bottom")
		(17 "Dwgs.User" user "User.Drawings")
		(19 "Cmts.User" user "User.Comments")
		(21 "Eco1.User" user "User.Eco1")
		(23 "Eco2.User" user "User.Eco2")
		(25 "Edge.Cuts" user "Board Geometry/Outline")
		(27 "Margin" user)
		(31 "F.CrtYd" user "Package Geometry/Place Bound Top")
		(29 "B.CrtYd" user "Package Geometry/Place Bound Bottom")
		(35 "F.Fab" user "Ref Des/Assembly Top")
		(33 "B.Fab" user "Ref Des/Assembly Bottom")
	)
	(footprint ""
		(layer "B.Cu")
		(at 176.25568 -82.677 -90)
		(property "Reference" "R6P12"
			(at 0 0 90)
			(layer "B.SilkS")
			(hide yes)
			(effects
				(font
					(size 1.27 1.27)
				)
				(justify mirror)
			)
		)
		(property "Value" ""
			(at 0 0 90)
			(layer "B.Fab")
			(effects
				(font
					(size 1.27 1.27)
				)
				(justify mirror)
			)
		)
		(duplicate_pad_numbers_are_jumpers no)
		(fp_poly
			(pts
				(xy 0.2794 -0.1016) (xy -0.2794 -0.1016) (xy -0.2794 0.9906) (xy 0.2794 0.9906)
			)
			(stroke
				(width 0)
				(type default)
			)
			(fill no)
			(layer "B.CrtYd")
		)
		(fp_line
			(start -0.2794 0.9906)
			(end -0.2794 -0.1016)
			(stroke
				(width 0.1)
				(type default)
			)
			(layer "B.Fab")
		)
		(fp_line
			(start 0.2794 0.9906)
			(end -0.2794 0.9906)
			(stroke
				(width 0.1)
				(type default)
			)
			(layer "B.Fab")
		)
		(fp_line
			(start -0.2794 -0.1016)
			(end 0.2794 -0.1016)
			(stroke
				(width 0.1)
				(type default)
			)
			(layer "B.Fab")
		)
		(fp_line
			(start 0.2794 -0.1016)
			(end 0.2794 0.9906)
			(stroke
				(width 0.1)
				(type default)
			)
			(layer "B.Fab")
		)
		(pad "1" smd rect
			(at 0 0 90)
			(size 0.508 0.508)
			(layers "B.Cu" "B.Mask" "B.Paste")
			(net "CLK_100M_CPU0_BCLK2_DN")
		)
		(pad "2" smd rect
			(at 0 0.889 90)
			(size 0.508 0.508)
			(layers "B.Cu" "B.Mask" "B.Paste")
			(net "GND")
		)
		(zone
			(layer "B.Cu")
			(hatch none 0.5)
			(connect_pads
				(clearance 0)
			)
			(min_thickness 0.25)
			(keepout
				(tracks not_allowed)
				(vias allowed)
				(pads allowed)
				(copperpour not_allowed)
				(footprints allowed)
			)
			(placement
				(enabled no)
				(sheetname "")
			)
			(fill
				(thermal_gap 0.5)
				(thermal_bridge_width 0.5)
				(island_removal_mode 0)
			)
			(polygon
				(pts
					(xy 175.62068 -82.423) (xy 175.62068 -82.931) (xy 176.00168 -82.931) (xy 176.00168 -82.423)
				)
			)
		)
		(zone
			(layer "B.Cu")
			(hatch none 0.5)
			(connect_pads
				(clearance 0)
			)
			(min_thickness 0.25)
			(keepout
				(tracks allowed)
				(vias not_allowed)
				(pads allowed)
				(copperpour not_allowed)
				(footprints allowed)
			)
			(placement
				(enabled no)
				(sheetname "")
			)
			(fill
				(thermal_gap 0.5)
				(thermal_bridge_width 0.5)
				(island_removal_mode 0)
			)
			(polygon
				(pts
					(xy 176.00168 -82.423) (xy 176.00168 -82.931) (xy 175.62068 -82.931) (xy 175.62068 -82.423)
				)
			)
		)
	)
	(footprint ""
		(layer "B.Cu")
		(at 169.799 -85.344)
		(property "Reference" "C6P4"
			(at 0 0 0)
			(layer "B.SilkS")
			(hide yes)
			(effects
				(font
					(size 1.27 1.27)
				)
				(justify mirror)
			)
		)
		(property "Value" ""
			(at 0 0 0)
			(layer "B.Fab")
			(effects
				(font
					(size 1.27 1.27)
				)
				(justify mirror)
			)
		)
		(duplicate_pad_numbers_are_jumpers no)
		(fp_poly
			(pts
				(xy -0.3048 -0.1016) (xy -0.3048 0.9906) (xy 0.3048 0.9906) (xy 0.3048 -0.1016)
			)
			(stroke
				(width 0)
				(type default)
			)
			(fill no)
			(layer "B.CrtYd")
		)
		(fp_line
			(start -0.3048 -0.1016)
			(end 0.3048 -0.1016)
			(stroke
				(width 0.1)
				(type default)
			)
			(layer "B.Fab")
		)
		(fp_line
			(start -0.3048 0.9906)
			(end -0.3048 -0.1016)
			(stroke
				(width 0.1)
				(type default)
			)
			(layer "B.Fab")
		)
		(fp_line
			(start 0.3048 -0.1016)
			(end 0.3048 0.9906)
			(stroke
				(width 0.1)
				(type default)
			)
			(layer "B.Fab")
		)
		(fp_line
			(start 0.3048 0.9906)
			(end -0.3048 0.9906)
			(stroke
				(width 0.1)
				(type default)
			)
			(layer "B.Fab")
		)
		(pad "1" smd rect
			(at 0 0 180)
			(size 0.508 0.508)
			(layers "B.Cu" "B.Mask" "B.Paste")
			(net "P3V3_DB1200")
		)
		(pad "2" smd rect
			(at 0 0.889 180)
			(size 0.508 0.508)
			(layers "B.Cu" "B.Mask" "B.Paste")
			(net "GND")
		)
		(zone
			(layer "B.Cu")
			(hatch none 0.5)
			(connect_pads
				(clearance 0)
			)
			(min_thickness 0.25)
			(keepout
				(tracks allowed)
				(vias not_allowed)
				(pads allowed)
				(copperpour not_allowed)
				(footprints allowed)
			)
			(placement
				(enabled no)
				(sheetname "")
			)
			(fill
				(thermal_gap 0.5)
				(thermal_bridge_width 0.5)
				(island_removal_mode 0)
			)
			(polygon
				(pts
					(xy 170.053 -85.09) (xy 169.545 -85.09) (xy 169.545 -84.709) (xy 170.053 -84.709)
				)
			)
		)
		(zone
			(layer "B.Cu")
			(hatch none 0.5)
			(connect_pads
				(clearance 0)
			)
			(min_thickness 0.25)
			(keepout
				(tracks not_allowed)
				(vias allowed)
				(pads allowed)
				(copperpour not_allowed)
				(footprints allowed)
			)
			(placement
				(enabled no)
				(sheetname "")
			)
			(fill
				(thermal_gap 0.5)
				(thermal_bridge_width 0.5)
				(island_removal_mode 0)
			)
			(polygon
				(pts
					(xy 170.053 -84.709) (xy 169.545 -84.709) (xy 169.545 -85.09) (xy 170.053 -85.09)
				)
			)
		)
	)
	(footprint ""
		(layer "B.Cu")
		(at 409.2702 -126.2888 90)
		(property "Reference" "FB2M1"
			(at 0 0 90)
			(layer "B.SilkS")
			(hide yes)
			(effects
				(font
					(size 1.27 1.27)
				)
				(justify mirror)
			)
		)
		(property "Value" ""
			(at 0 0 90)
			(layer "B.Fab")
			(effects
				(font
					(size 1.27 1.27)
				)
				(justify mirror)
			)
		)
		(duplicate_pad_numbers_are_jumpers no)
		(fp_poly
			(pts
				(xy 0.15113 -0.47498) (xy -1.59893 -0.47498) (xy -1.59893 0.47498) (xy 0.15113 0.47498)
			)
			(stroke
				(width 0)
				(type default)
			)
			(fill no)
			(layer "B.CrtYd")
		)
		(fp_line
			(start 0.15113 -0.47498)
			(end -1.59893 -0.47498)
			(stroke
				(width 0.1)
				(type default)
			)
			(layer "B.Fab")
		)
		(fp_line
			(start -1.59893 -0.47498)
			(end -1.59893 0.47498)
			(stroke
				(width 0.1)
				(type default)
			)
			(layer "B.Fab")
		)
		(fp_line
			(start 0.15113 0.47498)
			(end 0.15113 -0.47498)
			(stroke
				(width 0.1)
				(type default)
			)
			(layer "B.Fab")
		)
		(fp_line
			(start -1.59893 0.47498)
			(end 0.15113 0.47498)
			(stroke
				(width 0.1)
				(type default)
			)
			(layer "B.Fab")
		)
		(pad "1" smd rect
			(at 0 0 270)
			(size 0.9398 0.9398)
			(layers "B.Cu" "B.Mask" "B.Paste")
			(net "P1V05_PCH_STBY")
		)
		(pad "2" smd rect
			(at -1.4478 0 270)
			(size 0.9398 0.9398)
			(layers "B.Cu" "B.Mask" "B.Paste")
			(net "P1V05_PCH_STBY_WM20_PLL")
		)
		(zone
			(layer "B.Cu")
			(hatch none 0.5)
			(connect_pads
				(clearance 0)
			)
			(min_thickness 0.25)
			(keepout
				(tracks not_allowed)
				(vias allowed)
				(pads allowed)
				(copperpour not_allowed)
				(footprints allowed)
			)
			(placement
				(enabled no)
				(sheetname "")
			)
			(fill
				(thermal_gap 0.5)
				(thermal_bridge_width 0.5)
				(island_removal_mode 0)
			)
			(polygon
				(pts
					(xy 409.7401 -125.8189) (xy 408.8003 -125.8189) (xy 408.8003 -125.3109) (xy 409.7401 -125.3109)
				)
			)
		)
		(zone
			(layer "B.Cu")
			(hatch none 0.5)
			(connect_pads
				(clearance 0)
			)
			(min_thickness 0.25)
			(keepout
				(tracks allowed)
				(vias not_allowed)
				(pads allowed)
				(copperpour not_allowed)
				(footprints allowed)
			)
			(placement
				(enabled no)
				(sheetname "")
			)
			(fill
				(thermal_gap 0.5)
				(thermal_bridge_width 0.5)
				(island_removal_mode 0)
			)
			(polygon
				(pts
					(xy 409.7401 -125.8189) (xy 408.8003 -125.8189) (xy 408.8003 -125.3109) (xy 409.7401 -125.3109)
				)
			)
		)
	)
)
